(kicad_pcb
	(version 20241229)
	(generator "pcbnew")
	(generator_version "9.0")
	(general
		(thickness 1.711)
		(legacy_teardrops no)
	)
	(paper "A4")
	(title_block
		(title "Antmicro Baseboard for Jetson AGX Thor")
		(date "2026-02-18")
		(rev "1.1.0")
		(company "Antmicro Ltd")
		(comment 1 "www.antmicro.com")
		(comment 9 "footprints 343-345 of 1170")
	)
	(layers
		(0 "F.Cu" signal)
		(4 "In1.Cu" signal)
		(6 "In2.Cu" signal)
		(8 "In3.Cu" signal)
		(10 "In4.Cu" jumper)
		(12 "In5.Cu" signal)
		(14 "In6.Cu" signal)
		(16 "In7.Cu" signal)
		(18 "In8.Cu" signal)
		(2 "B.Cu" signal)
		(9 "F.Adhes" user "F.Adhesive")
		(11 "B.Adhes" user "B.Adhesive")
		(13 "F.Paste" user)
		(15 "B.Paste" user)
		(5 "F.SilkS" user "F.Silkscreen")
		(7 "B.SilkS" user "B.Silkscreen")
		(1 "F.Mask" user)
		(3 "B.Mask" user)
		(17 "Dwgs.User" user "User.Drawings")
		(19 "Cmts.User" user "User.Comments")
		(21 "Eco1.User" user "User.Eco1")
		(23 "Eco2.User" user "User.Eco2")
		(25 "Edge.Cuts" user)
		(27 "Margin" user)
		(31 "F.CrtYd" user "F.Courtyard")
		(29 "B.CrtYd" user "B.Courtyard")
		(35 "F.Fab" user)
		(33 "B.Fab" user)
	)
	(footprint "antmicro-footprints:USON-10_2.5x1mm_P0.5mm"
		(layer "F.Cu")
		(at 220.855 128.5)
		(descr "USON-10 2.5x1mm_ Pitch 0.5mm")
		(tags "USON-10 2.5x1mm Pitch 0.5mm")
		(property "Reference" "U25"
			(at 1.025 -4.24 90)
			(layer "F.SilkS")
			(effects
				(font
					(size 0.7 0.7)
					(thickness 0.15)
				)
				(justify right top)
			)
		)
		(property "Value" "TPD4E05U06QDQARQ1"
			(at 0.018 2.499 0)
			(layer "F.Fab")
			(effects
				(font
					(size 0.7 0.7)
					(thickness 0.15)
				)
				(justify left bottom)
			)
		)
		(property "Datasheet" "https://www.ti.com/lit/ds/symlink/tpd4e05u06-q1.pdf?HQS=dis-mous-null-mousermode-dsf-pf-null-wwe&ts=1663591265741&ref_url=https%253A%252F%252Fwww.mouser.com%252F"
			(at 0 0 0)
			(layer "F.Fab")
			(hide yes)
			(effects
				(font
					(size 1.27 1.27)
					(thickness 0.15)
				)
			)
		)
		(property "Description" "TVS diode array, 12 kV, USON-10, 5.5 V, 0.5 pF"
			(at 0 0 0)
			(layer "F.Fab")
			(hide yes)
			(effects
				(font
					(size 1.27 1.27)
					(thickness 0.15)
				)
			)
		)
		(property "Manufacturer" "Texas Instruments"
			(at 0 0 0)
			(unlocked yes)
			(layer "F.Fab")
			(hide yes)
			(effects
				(font
					(size 1 1)
					(thickness 0.15)
				)
			)
		)
		(property "MPN" "TPD4E05U06QDQARQ1"
			(at 0 0 0)
			(unlocked yes)
			(layer "F.Fab")
			(hide yes)
			(effects
				(font
					(size 1 1)
					(thickness 0.15)
				)
			)
		)
		(property "Author" "Antmicro"
			(at 0 0 0)
			(unlocked yes)
			(layer "F.Fab")
			(hide yes)
			(effects
				(font
					(size 1 1)
					(thickness 0.15)
				)
			)
		)
		(property "License" "Apache-2.0"
			(at 0 0 0)
			(unlocked yes)
			(layer "F.Fab")
			(hide yes)
			(effects
				(font
					(size 1 1)
					(thickness 0.15)
				)
			)
		)
		(sheetname "/USB Hub/")
		(sheetfile "usb_hub.kicad_sch")
		(attr smd)
		(fp_line
			(start 0.498 -1.401)
			(end -0.5 -1.401)
			(stroke
				(width 0.15)
				(type solid)
			)
			(layer "F.SilkS")
		)
		(fp_line
			(start 0.498 1.398)
			(end -0.5 1.398)
			(stroke
				(width 0.15)
				(type solid)
			)
			(layer "F.SilkS")
		)
		(fp_circle
			(center -0.68 -1.27)
			(end -0.63 -1.27)
			(stroke
				(width 0.15)
				(type solid)
			)
			(fill yes)
			(layer "F.SilkS")
		)
		(fp_rect
			(start -0.8 -1.5)
			(end 0.8 1.499)
			(stroke
				(width 0.05)
				(type solid)
			)
			(fill no)
			(layer "F.CrtYd")
		)
		(fp_line
			(start -0.5 -1)
			(end -0.5 1.249)
			(stroke
				(width 0.15)
				(type solid)
			)
			(layer "F.Fab")
		)
		(fp_line
			(start -0.5 1.249)
			(end 0.498 1.249)
			(stroke
				(width 0.15)
				(type solid)
			)
			(layer "F.Fab")
		)
		(fp_line
			(start -0.25 -1.25)
			(end -0.5 -1)
			(stroke
				(width 0.15)
				(type solid)
			)
			(layer "F.Fab")
		)
		(fp_line
			(start 0.498 -1.25)
			(end -0.25 -1.25)
			(stroke
				(width 0.15)
				(type solid)
			)
			(layer "F.Fab")
		)
		(fp_line
			(start 0.498 -1.25)
			(end 0.498 1.249)
			(stroke
				(width 0.15)
				(type solid)
			)
			(layer "F.Fab")
		)
		(fp_text user "License: Apache-2.0"
			(at -0.802 6.9 0)
			(layer "F.Fab")
			(effects
				(font
					(size 0.7 0.7)
					(thickness 0.15)
				)
				(justify left bottom)
			)
		)
		(fp_text user "Author: Antmicro"
			(at -0.802 5.7 0)
			(layer "F.Fab")
			(effects
				(font
					(size 0.7 0.7)
					(thickness 0.15)
				)
				(justify left bottom)
			)
		)
		(fp_text user "${REFERENCE}"
			(at -0.802 4.498 0)
			(layer "F.Fab")
			(effects
				(font
					(size 0.7 0.7)
					(thickness 0.15)
				)
				(justify left bottom)
			)
		)
		(pad "1" smd roundrect
			(at -0.387 -1 270)
			(size 0.25 0.55)
			(layers "F.Cu" "F.Mask" "F.Paste")
			(roundrect_rratio 0.25)
			(net 505 "/USB Hub/USBC4_D+")
			(pintype "passive")
		)
		(pad "2" smd roundrect
			(at -0.387 -0.5 270)
			(size 0.25 0.55)
			(layers "F.Cu" "F.Mask" "F.Paste")
			(roundrect_rratio 0.25)
			(net 499 "/USB Hub/USBC4_D-")
			(pintype "passive")
		)
		(pad "3" smd roundrect
			(at -0.387 0 270)
			(size 0.4 0.55)
			(layers "F.Cu" "F.Mask" "F.Paste")
			(roundrect_rratio 0.25)
			(net 1 "GND")
			(pintype "power_in")
		)
		(pad "4" smd roundrect
			(at -0.387 0.498 270)
			(size 0.25 0.55)
			(layers "F.Cu" "F.Mask" "F.Paste")
			(roundrect_rratio 0.25)
			(net 502 "/USB Hub/USBC4_CC_{2}")
			(pintype "passive")
		)
		(pad "5" smd roundrect
			(at -0.387 0.998 270)
			(size 0.25 0.55)
			(layers "F.Cu" "F.Mask" "F.Paste")
			(roundrect_rratio 0.25)
			(net 503 "/USB Hub/USBC4_CC_{1}")
			(pintype "passive")
		)
		(pad "6" smd roundrect
			(at 0.385 0.998 270)
			(size 0.25 0.55)
			(layers "F.Cu" "F.Mask" "F.Paste")
			(roundrect_rratio 0.25)
			(net 503 "/USB Hub/USBC4_CC_{1}")
			(pintype "passive")
		)
		(pad "7" smd roundrect
			(at 0.385 0.498 270)
			(size 0.25 0.55)
			(layers "F.Cu" "F.Mask" "F.Paste")
			(roundrect_rratio 0.25)
			(net 502 "/USB Hub/USBC4_CC_{2}")
			(pintype "passive")
		)
		(pad "8" smd roundrect
			(at 0.385 0 270)
			(size 0.4 0.55)
			(layers "F.Cu" "F.Mask" "F.Paste")
			(roundrect_rratio 0.25)
			(net 1 "GND")
			(pintype "passive")
		)
		(pad "9" smd roundrect
			(at 0.385 -0.5 270)
			(size 0.25 0.55)
			(layers "F.Cu" "F.Mask" "F.Paste")
			(roundrect_rratio 0.25)
			(net 499 "/USB Hub/USBC4_D-")
			(pintype "passive")
		)
		(pad "10" smd roundrect
			(at 0.385 -1 270)
			(size 0.25 0.55)
			(layers "F.Cu" "F.Mask" "F.Paste")
			(roundrect_rratio 0.25)
			(net 505 "/USB Hub/USBC4_D+")
			(pintype "passive")
		)
	)
	(footprint "antmicro-footprints:SOT-23-8"
		(layer "F.Cu")
		(at 161.404468 102.075 -90)
		(descr "http://www.ti.com/lit/ds/symlink/ina219.pdf")
		(property "Reference" "U22"
			(at -0.205 2.645 90)
			(layer "F.SilkS")
			(effects
				(font
					(size 0.7 0.7)
					(thickness 0.15)
				)
				(justify right top)
			)
		)
		(property "Value" "INA219AIDCNR"
			(at -2.925 2.8 90)
			(layer "F.Fab")
			(effects
				(font
					(size 0.7 0.7)
					(thickness 0.15)
				)
				(justify right top)
			)
		)
		(property "Datasheet" "https://www.ti.com/lit/ds/symlink/ina219.pdf?ts=1713856455637&ref_url=https%253A%252F%252Fwww.mouser.es%252F"
			(at 0 0 90)
			(layer "F.Fab")
			(hide yes)
			(effects
				(font
					(size 1.27 1.27)
					(thickness 0.15)
				)
			)
		)
		(property "Description" "Zerø-Drift, Bidirectional Current/Power Monitor With I2C Interface"
			(at 0 0 90)
			(layer "F.Fab")
			(hide yes)
			(effects
				(font
					(size 1.27 1.27)
					(thickness 0.15)
				)
			)
		)
		(property "Manufacturer" "Texas Instruments"
			(at 0 0 90)
			(unlocked yes)
			(layer "F.Fab")
			(hide yes)
			(effects
				(font
					(size 1 1)
					(thickness 0.15)
				)
			)
		)
		(property "MPN" "INA219AIDCNR"
			(at 0 0 90)
			(unlocked yes)
			(layer "F.Fab")
			(hide yes)
			(effects
				(font
					(size 1 1)
					(thickness 0.15)
				)
			)
		)
		(property "Author" "Antmicro"
			(at 0 0 90)
			(unlocked yes)
			(layer "F.Fab")
			(hide yes)
			(effects
				(font
					(size 1 1)
					(thickness 0.15)
				)
			)
		)
		(property "License" "Apache-2.0"
			(at 0 0 90)
			(unlocked yes)
			(layer "F.Fab")
			(hide yes)
			(effects
				(font
					(size 1 1)
					(thickness 0.15)
				)
			)
		)
		(component_classes
			(class "DCDC_SOM")
		)
		(sheetname "/DCDC/")
		(sheetfile "dcdc.kicad_sch")
		(attr smd)
		(fp_line
			(start -0.987 1.6)
			(end -0.987 1.324)
			(stroke
				(width 0.15)
				(type solid)
			)
			(layer "F.SilkS")
		)
		(fp_line
			(start -0.613 1.6)
			(end -0.987 1.6)
			(stroke
				(width 0.15)
				(type solid)
			)
			(layer "F.SilkS")
		)
		(fp_line
			(start 1 1.6)
			(end 0.6 1.6)
			(stroke
				(width 0.15)
				(type solid)
			)
			(layer "F.SilkS")
		)
		(fp_line
			(start 1 1.3)
			(end 1 1.6)
			(stroke
				(width 0.15)
				(type solid)
			)
			(layer "F.SilkS")
		)
		(fp_line
			(start -1 -1.3)
			(end -1 -1.6)
			(stroke
				(width 0.15)
				(type solid)
			)
			(layer "F.SilkS")
		)
		(fp_line
			(start 1 -1.3)
			(end 1 -1.6)
			(stroke
				(width 0.15)
				(type solid)
			)
			(layer "F.SilkS")
		)
		(fp_line
			(start -1 -1.6)
			(end -0.6 -1.6)
			(stroke
				(width 0.15)
				(type solid)
			)
			(layer "F.SilkS")
		)
		(fp_line
			(start 1 -1.6)
			(end 0.625 -1.6)
			(stroke
				(width 0.15)
				(type solid)
			)
			(layer "F.SilkS")
		)
		(fp_circle
			(center -1.3 -1.4)
			(end -1.25 -1.4)
			(stroke
				(width 0.15)
				(type solid)
			)
			(fill yes)
			(layer "F.SilkS")
		)
		(fp_rect
			(start -1.9 -1.75)
			(end 1.898 1.75)
			(stroke
				(width 0.05)
				(type solid)
			)
			(fill no)
			(layer "F.CrtYd")
		)
		(fp_line
			(start -1.4 -1.25)
			(end -1.2 -1.45)
			(stroke
				(width 0.15)
				(type solid)
			)
			(layer "F.Fab")
		)
		(fp_rect
			(start -1.401 -1.45)
			(end 1.398 1.449)
			(stroke
				(width 0.15)
				(type solid)
			)
			(fill no)
			(layer "F.Fab")
		)
		(fp_text user "Author: Antmicro"
			(at -2.925 7.2 90)
			(layer "F.Fab")
			(effects
				(font
					(size 0.7 0.7)
					(thickness 0.15)
				)
				(justify right top)
			)
		)
		(fp_text user "License: Apache-2.0"
			(at -2.925 6 90)
			(layer "F.Fab")
			(effects
				(font
					(size 0.7 0.7)
					(thickness 0.15)
				)
				(justify right top)
			)
		)
		(fp_text user "${REFERENCE}"
			(at -2.925 4.8 90)
			(layer "F.Fab")
			(effects
				(font
					(size 0.7 0.7)
					(thickness 0.15)
				)
				(justify right top)
			)
		)
		(pad "1" smd roundrect
			(at -1.3 -0.975 180)
			(size 0.45 1.1)
			(layers "F.Cu" "F.Mask" "F.Paste")
			(roundrect_rratio 0.25)
			(net 1283 "Net-(U22-IN+)")
			(pinfunction "IN+")
			(pintype "passive")
		)
		(pad "2" smd roundrect
			(at -1.3 -0.325 180)
			(size 0.45 1.1)
			(layers "F.Cu" "F.Mask" "F.Paste")
			(roundrect_rratio 0.25)
			(net 1187 "Net-(U22-IN-)")
			(pinfunction "IN-")
			(pintype "passive")
		)
		(pad "3" smd roundrect
			(at -1.3 0.325 180)
			(size 0.45 1.1)
			(layers "F.Cu" "F.Mask" "F.Paste")
			(roundrect_rratio 0.25)
			(net 1 "GND")
			(pinfunction "GND")
			(pintype "power_in")
		)
		(pad "4" smd roundrect
			(at -1.3 0.975 180)
			(size 0.45 1.1)
			(layers "F.Cu" "F.Mask" "F.Paste")
			(roundrect_rratio 0.25)
			(net 4 "+3V3_AON")
			(pinfunction "V_{S}")
			(pintype "power_in")
		)
		(pad "5" smd roundrect
			(at 1.3 0.975 180)
			(size 0.45 1.1)
			(layers "F.Cu" "F.Mask" "F.Paste")
			(roundrect_rratio 0.25)
			(net 853 "/I2C_{SYS}.SCL")
			(pinfunction "SCL")
			(pintype "open_collector")
		)
		(pad "6" smd roundrect
			(at 1.3 0.325 180)
			(size 0.45 1.1)
			(layers "F.Cu" "F.Mask" "F.Paste")
			(roundrect_rratio 0.25)
			(net 850 "/I2C_{SYS}.SDA")
			(pinfunction "SDA")
			(pintype "open_collector")
		)
		(pad "7" smd roundrect
			(at 1.3 -0.325 180)
			(size 0.45 1.1)
			(layers "F.Cu" "F.Mask" "F.Paste")
			(roundrect_rratio 0.25)
			(net 4 "+3V3_AON")
			(pinfunction "A0")
			(pintype "passive")
		)
		(pad "8" smd roundrect
			(at 1.3 -0.975 180)
			(size 0.45 1.1)
			(layers "F.Cu" "F.Mask" "F.Paste")
			(roundrect_rratio 0.25)
			(net 4 "+3V3_AON")
			(pinfunction "A1")
			(pintype "passive")
		)
	)
	(footprint "antmicro-footprints:C_0805_2012Metric"
		(layer "F.Cu")
		(at 174.99 73.32 -90)
		(descr "Capacitor SMD 0805")
		(tags "capacitor SMD 0805")
		(property "Reference" "C289"
			(at 1.81 9.64 90)
			(layer "F.SilkS")
			(effects
				(font
					(size 0.7 0.7)
					(thickness 0.15)
				)
				(justify right top)
			)
		)
		(property "Value" "C_22u_25V_0805"
			(at -2.055717 1.963152 90)
			(layer "F.Fab")
			(effects
				(font
					(size 0.7 0.7)
					(thickness 0.15)
				)
				(justify right top)
			)
		)
		(property "Datasheet" "https://product.samsungsem.com/mlcc/CL21A226MAYNNN.do"
			(at 0 0 90)
			(layer "F.Fab")
			(hide yes)
			(effects
				(font
					(size 1.27 1.27)
					(thickness 0.15)
				)
			)
		)
		(property "Description" "SMT Multilayer Ceramic Capacitor, 22uF, +/-20%, 25V, X5R, 0805 [2012 Metric]"
			(at 0 0 90)
			(layer "F.Fab")
			(hide yes)
			(effects
				(font
					(size 1.27 1.27)
					(thickness 0.15)
				)
			)
		)
		(property "MPN" "CL21A226MAYNNNE"
			(at 0 0 270)
			(unlocked yes)
			(layer "F.Fab")
			(hide yes)
			(effects
				(font
					(size 1 1)
					(thickness 0.15)
				)
			)
		)
		(property "Manufacturer" "Samsung Electro-Mechanics"
			(at 0 0 270)
			(unlocked yes)
			(layer "F.Fab")
			(hide yes)
			(effects
				(font
					(size 1 1)
					(thickness 0.15)
				)
			)
		)
		(property "License" "Apache-2.0"
			(at 0 0 270)
			(unlocked yes)
			(layer "F.Fab")
			(hide yes)
			(effects
				(font
					(size 1 1)
					(thickness 0.15)
				)
			)
		)
		(property "Author" "Antmicro"
			(at 0 0 270)
			(unlocked yes)
			(layer "F.Fab")
			(hide yes)
			(effects
				(font
					(size 1 1)
					(thickness 0.15)
				)
			)
		)
		(property "Val" "22u"
			(at 0 0 270)
			(unlocked yes)
			(layer "F.Fab")
			(hide yes)
			(effects
				(font
					(size 1 1)
					(thickness 0.15)
				)
			)
		)
		(property "Voltage" "25V"
			(at 0 0 270)
			(unlocked yes)
			(layer "F.Fab")
			(hide yes)
			(effects
				(font
					(size 1 1)
					(thickness 0.15)
				)
			)
		)
		(property "Dielectric" "X5R"
			(at 0 0 270)
			(unlocked yes)
			(layer "F.Fab")
			(hide yes)
			(effects
				(font
					(size 1 1)
					(thickness 0.15)
				)
			)
		)
		(property "Public" "False"
			(at 0 0 270)
			(unlocked yes)
			(layer "F.Fab")
			(hide yes)
			(effects
				(font
					(size 1 1)
					(thickness 0.15)
				)
			)
		)
		(component_classes
			(class "DCDC_20V")
		)
		(sheetname "/DCDC/")
		(sheetfile "dcdc.kicad_sch")
		(attr smd)
		(fp_line
			(start -0.3 0.7)
			(end 0.3 0.7)
			(stroke
				(width 0.15)
				(type solid)
			)
			(layer "F.SilkS")
		)
		(fp_line
			(start -0.3 -0.7)
			(end 0.3 -0.7)
			(stroke
				(width 0.15)
				(type solid)
			)
			(layer "F.SilkS")
		)
		(fp_rect
			(start 1.95 -0.9)
			(end -1.95 0.9)
			(stroke
				(width 0.05)
				(type default)
			)
			(fill no)
			(layer "F.CrtYd")
		)
		(fp_rect
			(start -0.95 -0.675)
			(end 0.95 0.675)
			(stroke
				(width 0.15)
				(type solid)
			)
			(fill no)
			(layer "F.Fab")
		)
		(fp_text user "${REFERENCE}"
			(at -1.9 3.947 90)
			(layer "F.Fab")
			(effects
				(font
					(size 0.7 0.7)
					(thickness 0.15)
				)
				(justify right top)
			)
		)
		(fp_text user "License: Apache-2.0"
			(at -1.9 4.947 90)
			(layer "F.Fab")
			(effects
				(font
					(size 0.7 0.7)
					(thickness 0.15)
				)
				(justify right top)
			)
		)
		(fp_text user "Author: Antmicro"
			(at -1.9 5.947 90)
			(layer "F.Fab")
			(effects
				(font
					(size 0.7 0.7)
					(thickness 0.15)
				)
				(justify right top)
			)
		)
		(pad "1" smd roundrect
			(at -1.1 0 270)
			(size 1.2 1.3)
			(layers "F.Cu" "F.Mask" "F.Paste")
			(roundrect_rratio 0.25)
			(net 1 "GND")
			(pintype "passive")
		)
		(pad "2" smd roundrect
			(at 1.1 0 270)
			(size 1.2 1.3)
			(layers "F.Cu" "F.Mask" "F.Paste")
			(roundrect_rratio 0.25)
			(net 1105 "/DCDC/20V_OUT")
			(pintype "passive")
		)
	)
)
